(kicad_pcb
	(version 20221018)
	(generator pcbnew)
	(general
    (thickness 1.518)
  )
	(paper "A4")
	(title_block
    (title "Kria K26 Devboard")
    (date "2024-03-26")
    (rev "1.2.5")
    (comment 1 "www.antmicro.com")
    (comment 2 "Antmicro Ltd.")
		(comment 9 "footprints 332-341 of 660")
	)
	(layers
    (0 "F.Cu" mixed)
    (1 "In1.Cu" power)
    (2 "In2.Cu" mixed)
    (3 "In3.Cu" power)
    (4 "In4.Cu" mixed)
    (5 "In5.Cu" power)
    (6 "In6.Cu" mixed)
    (31 "B.Cu" power)
    (32 "B.Adhes" user "B.Adhesive")
    (33 "F.Adhes" user "F.Adhesive")
    (34 "B.Paste" user)
    (35 "F.Paste" user)
    (36 "B.SilkS" user "B.Silkscreen")
    (37 "F.SilkS" user "F.Silkscreen")
    (38 "B.Mask" user)
    (39 "F.Mask" user)
    (40 "Dwgs.User" user "User.Drawings")
    (41 "Cmts.User" user "User.Comments")
    (42 "Eco1.User" user "User.Eco1")
    (43 "Eco2.User" user "User.Eco2")
    (44 "Edge.Cuts" user)
    (45 "Margin" user)
    (46 "B.CrtYd" user "B.Courtyard")
    (47 "F.CrtYd" user "F.Courtyard")
    (48 "B.Fab" user)
    (49 "F.Fab" user)
  )
	(footprint "kria-k26-devboard-footprints:C_0603_1608Metric" (layer "F.Cu")
    (at 166.75 128.589999 -90)
    (descr "Capacitor SMD 0603")
    (tags "capacitor 0603")
    (property "Author" "Antmicro")
    (property "Dielectric" "")
    (property "License" "Apache-2.0")
    (property "MPN" "CL10A226MO7JZNC")
    (property "Manufacturer" "Samsung")
    (property "Sheetfile" "dc-dc-conventers.kicad_sch")
    (property "Sheetname" "DC/DC conventers")
    (property "Val" "22u/16V")
    (property "Voltage" "")
    (property "ki_description" " ")
    (attr smd)
    (fp_text reference "C200" (at -1.565 3.55 -90) (layer "F.SilkS")
        (effects (font (size 0.7 0.7) (thickness 0.15)) (justify left bottom))
    )
    (fp_text value "C_22u_16V_0603" (at 0 1.6 -90) (layer "F.Fab") hide
        (effects (font (size 0.7 0.7) (thickness 0.15)) (justify left bottom))
    )
    (fp_text user "${REFERENCE}" (at -1.682 3.895 -90) (layer "F.Fab") hide
        (effects (font (size 0.7 0.7) (thickness 0.15)) (justify left bottom))
    )
    (fp_text user "Author: Antmicro" (at -1.682 4.894 -90) (layer "F.Fab") hide
        (effects (font (size 0.7 0.7) (thickness 0.15)) (justify left bottom))
    )
    (fp_text user "License: Apache-2.0" (at -1.682 5.895 -90) (layer "F.Fab") hide
        (effects (font (size 0.7 0.7) (thickness 0.15)) (justify left bottom))
    )
    (fp_line (start -0.3 -0.3) (end 0.3 -0.3)
      (stroke (width 0.15) (type solid)) (layer "F.SilkS"))
    (fp_line (start -0.3 0.3) (end 0.3 0.3)
      (stroke (width 0.15) (type solid)) (layer "F.SilkS"))
    (fp_rect (start -1.24 -0.7) (end 1.24 0.7)
      (stroke (width 0.05) (type solid)) (fill none) (layer "F.CrtYd"))
    (fp_rect (start -0.8 -0.4) (end 0.8 0.4)
      (stroke (width 0.15) (type solid)) (fill none) (layer "F.Fab"))
    (pad "1" smd roundrect (at -0.7 0 270) (size 0.6 0.8) (layers "F.Cu" "F.Paste" "F.Mask") (roundrect_rratio 0.2)
      (net 773 "/Power Supply/DC/DC conventers/SOM_5V_OUT") (pintype "passive"))
    (pad "2" smd roundrect (at 0.7 0 270) (size 0.6 0.8) (layers "F.Cu" "F.Paste" "F.Mask") (roundrect_rratio 0.2)
      (net 1 "GND") (pintype "passive"))
  )
	(footprint "kria-k26-devboard-footprints:C_0402_1005Metric" (layer "F.Cu")
    (at 173.825 127.725 -90)
    (descr "Capacitor SMD 0402")
    (tags "capacitor SMD 0402")
    (property "Author" "Antmicro")
    (property "Dielectric" "")
    (property "License" "Apache-2.0")
    (property "MPN" "CC0402JRNPO9BN220")
    (property "Manufacturer" "Yaego")
    (property "Sheetfile" "dc-dc-conventers.kicad_sch")
    (property "Sheetname" "DC/DC conventers")
    (property "Val" "22p")
    (property "Voltage" "")
    (property "ki_description" " ")
    (attr smd)
    (fp_text reference "C194" (at 1.395 2.595 -90) (layer "F.SilkS")
        (effects (font (size 0.7 0.7) (thickness 0.15)) (justify left bottom))
    )
    (fp_text value "C_22p_0402" (at 0 1.4 -90) (layer "F.Fab") hide
        (effects (font (size 0.7 0.7) (thickness 0.15)) (justify left bottom))
    )
    (fp_text user "License: Apache-2.0" (at -0.932 5.17 -90) (layer "F.Fab") hide
        (effects (font (size 0.7 0.7) (thickness 0.15)) (justify left bottom))
    )
    (fp_text user "${REFERENCE}" (at -0.932 3.168 -90) (layer "F.Fab") hide
        (effects (font (size 0.7 0.7) (thickness 0.15)) (justify left bottom))
    )
    (fp_text user "Author: Antmicro" (at -0.932 4.17 -90) (layer "F.Fab") hide
        (effects (font (size 0.7 0.7) (thickness 0.15)) (justify left bottom))
    )
    (fp_rect (start -0.94 -0.47) (end 0.94 0.47)
      (stroke (width 0.05) (type solid)) (fill none) (layer "F.CrtYd"))
    (fp_rect (start -0.499 -0.249) (end 0.499 0.249)
      (stroke (width 0.15) (type solid)) (fill none) (layer "F.Fab"))
    (pad "1" smd roundrect (at -0.484 0 270) (size 0.59 0.64) (layers "F.Cu" "F.Paste" "F.Mask") (roundrect_rratio 0.25)
      (net 255 "Net-(U48-FB)") (pintype "passive"))
    (pad "2" smd roundrect (at 0.484 0 270) (size 0.59 0.64) (layers "F.Cu" "F.Paste" "F.Mask") (roundrect_rratio 0.25)
      (net 774 "/Power Supply/DC/DC conventers/SOM_5V_FB") (pintype "passive"))
  )
	(footprint "kria-k26-devboard-footprints:C_0603_1608Metric" (layer "F.Cu")
    (at 168.2 128.59 -90)
    (descr "Capacitor SMD 0603")
    (tags "capacitor 0603")
    (property "Author" "Antmicro")
    (property "Dielectric" "")
    (property "License" "Apache-2.0")
    (property "MPN" "CL10A226MO7JZNC")
    (property "Manufacturer" "Samsung")
    (property "Sheetfile" "dc-dc-conventers.kicad_sch")
    (property "Sheetname" "DC/DC conventers")
    (property "Val" "22u/16V")
    (property "Voltage" "")
    (property "ki_description" " ")
    (attr smd)
    (fp_text reference "C198" (at -1.565001 3.91 -90) (layer "F.SilkS")
        (effects (font (size 0.7 0.7) (thickness 0.15)) (justify left bottom))
    )
    (fp_text value "C_22u_16V_0603" (at 0 1.6 -90) (layer "F.Fab") hide
        (effects (font (size 0.7 0.7) (thickness 0.15)) (justify left bottom))
    )
    (fp_text user "License: Apache-2.0" (at -1.682 5.895 -90) (layer "F.Fab") hide
        (effects (font (size 0.7 0.7) (thickness 0.15)) (justify left bottom))
    )
    (fp_text user "${REFERENCE}" (at -1.682 3.895 -90) (layer "F.Fab") hide
        (effects (font (size 0.7 0.7) (thickness 0.15)) (justify left bottom))
    )
    (fp_text user "Author: Antmicro" (at -1.682 4.894 -90) (layer "F.Fab") hide
        (effects (font (size 0.7 0.7) (thickness 0.15)) (justify left bottom))
    )
    (fp_line (start -0.3 -0.3) (end 0.3 -0.3)
      (stroke (width 0.15) (type solid)) (layer "F.SilkS"))
    (fp_line (start -0.3 0.3) (end 0.3 0.3)
      (stroke (width 0.15) (type solid)) (layer "F.SilkS"))
    (fp_rect (start -1.24 -0.7) (end 1.24 0.7)
      (stroke (width 0.05) (type solid)) (fill none) (layer "F.CrtYd"))
    (fp_rect (start -0.8 -0.4) (end 0.8 0.4)
      (stroke (width 0.15) (type solid)) (fill none) (layer "F.Fab"))
    (pad "1" smd roundrect (at -0.7 0 270) (size 0.6 0.8) (layers "F.Cu" "F.Paste" "F.Mask") (roundrect_rratio 0.2)
      (net 773 "/Power Supply/DC/DC conventers/SOM_5V_OUT") (pintype "passive"))
    (pad "2" smd roundrect (at 0.7 0 270) (size 0.6 0.8) (layers "F.Cu" "F.Paste" "F.Mask") (roundrect_rratio 0.2)
      (net 1 "GND") (pintype "passive"))
  )
	(footprint "kria-k26-devboard-footprints:TP_SMD_0.75mm" (layer "F.Cu")
    (at 87.65 123.05)
    (property "Author" "Antmicro")
    (property "License" "Apache-2.0")
    (property "MPN" "")
    (property "Manufacturer" "")
    (property "Sheetfile" "camera.kicad_sch")
    (property "Sheetname" "Camera interface")
    (property "ki_description" "Test Point 0.75mm")
    (attr exclude_from_pos_files)
    (fp_text reference "TP1" (at -0.93 1.23) (layer "F.SilkS")
        (effects (font (size 0.7 0.7) (thickness 0.15)) (justify left bottom))
    )
    (fp_text value "TP_0.75mm_SMD" (at 0 1.2) (layer "F.Fab") hide
        (effects (font (size 0.7 0.7) (thickness 0.15)) (justify left bottom))
    )
    (fp_text user "${REFERENCE}" (at -0.4 2.7) (layer "F.Fab") hide
        (effects (font (size 0.7 0.7) (thickness 0.15)) (justify left bottom))
    )
    (fp_text user "Author: Antmicro" (at -0.4 3.901) (layer "F.Fab") hide
        (effects (font (size 0.7 0.7) (thickness 0.15)) (justify left bottom))
    )
    (fp_text user "License: Apache-2.0" (at -0.4 5.101) (layer "F.Fab") hide
        (effects (font (size 0.7 0.7) (thickness 0.15)) (justify left bottom))
    )
    (pad "1" smd circle (at 0 0) (size 0.75 0.75) (layers "F.Cu" "F.Mask")
      (net 410 "/Camera interface/HDA00_CC") (pinfunction "1") (pintype "passive"))
  )
	(footprint "kria-k26-devboard-footprints:TP_SMD_0.75mm" (layer "F.Cu")
    (at 87.65 122.05)
    (property "Author" "Antmicro")
    (property "License" "Apache-2.0")
    (property "MPN" "")
    (property "Manufacturer" "")
    (property "Sheetfile" "camera.kicad_sch")
    (property "Sheetname" "Camera interface")
    (property "ki_description" "Test Point 0.75mm")
    (attr exclude_from_pos_files)
    (fp_text reference "TP2" (at -0.94 -0.44) (layer "F.SilkS")
        (effects (font (size 0.7 0.7) (thickness 0.15)) (justify left bottom))
    )
    (fp_text value "TP_0.75mm_SMD" (at 0 1.2) (layer "F.Fab") hide
        (effects (font (size 0.7 0.7) (thickness 0.15)) (justify left bottom))
    )
    (fp_text user "License: Apache-2.0" (at -0.4 5.101) (layer "F.Fab") hide
        (effects (font (size 0.7 0.7) (thickness 0.15)) (justify left bottom))
    )
    (fp_text user "${REFERENCE}" (at -0.4 2.7) (layer "F.Fab") hide
        (effects (font (size 0.7 0.7) (thickness 0.15)) (justify left bottom))
    )
    (fp_text user "Author: Antmicro" (at -0.4 3.901) (layer "F.Fab") hide
        (effects (font (size 0.7 0.7) (thickness 0.15)) (justify left bottom))
    )
    (pad "1" smd circle (at 0 0) (size 0.75 0.75) (layers "F.Cu" "F.Mask")
      (net 225 "/Camera interface/HDA01") (pinfunction "1") (pintype "passive"))
  )
	(footprint "kria-k26-devboard-footprints:TP_SMD_0.75mm" (layer "F.Cu")
    (at 83.45 116.9)
    (property "Author" "Antmicro")
    (property "License" "Apache-2.0")
    (property "MPN" "")
    (property "Manufacturer" "")
    (property "Sheetfile" "camera.kicad_sch")
    (property "Sheetname" "Camera interface")
    (property "ki_description" "Test Point 0.75mm")
    (attr exclude_from_pos_files)
    (fp_text reference "TP3" (at 0.26 0.23) (layer "F.SilkS")
        (effects (font (size 0.7 0.7) (thickness 0.15)) (justify left bottom))
    )
    (fp_text value "TP_0.75mm_SMD" (at 0 1.2) (layer "F.Fab") hide
        (effects (font (size 0.7 0.7) (thickness 0.15)) (justify left bottom))
    )
    (fp_text user "License: Apache-2.0" (at -0.4 5.101) (layer "F.Fab") hide
        (effects (font (size 0.7 0.7) (thickness 0.15)) (justify left bottom))
    )
    (fp_text user "${REFERENCE}" (at -0.4 2.7) (layer "F.Fab") hide
        (effects (font (size 0.7 0.7) (thickness 0.15)) (justify left bottom))
    )
    (fp_text user "Author: Antmicro" (at -0.4 3.901) (layer "F.Fab") hide
        (effects (font (size 0.7 0.7) (thickness 0.15)) (justify left bottom))
    )
    (pad "1" smd circle (at 0 0) (size 0.75 0.75) (layers "F.Cu" "F.Mask")
      (net 322 "PL_1V8") (pinfunction "1") (pintype "passive"))
  )
	(footprint "kria-k26-devboard-footprints:TP_SMD_0.75mm" (layer "F.Cu")
    (at 144.3 110.7)
    (property "Author" "Antmicro")
    (property "License" "Apache-2.0")
    (property "MPN" "")
    (property "Manufacturer" "")
    (property "Sheetfile" "debug.kicad_sch")
    (property "Sheetname" "Debug and JTAG")
    (property "ki_description" "Test Point 0.75mm")
    (attr exclude_from_pos_files)
    (fp_text reference "TP25" (at 0.85 -1.76 90) (layer "F.SilkS")
        (effects (font (size 0.7 0.7) (thickness 0.15)) (justify left bottom))
    )
    (fp_text value "TP_0.75mm_SMD" (at 0 1.2) (layer "F.Fab") hide
        (effects (font (size 0.7 0.7) (thickness 0.15)) (justify left bottom))
    )
    (fp_text user "${REFERENCE}" (at -0.4 2.7) (layer "F.Fab") hide
        (effects (font (size 0.7 0.7) (thickness 0.15)) (justify left bottom))
    )
    (fp_text user "Author: Antmicro" (at -0.4 3.901) (layer "F.Fab") hide
        (effects (font (size 0.7 0.7) (thickness 0.15)) (justify left bottom))
    )
    (fp_text user "License: Apache-2.0" (at -0.4 5.101) (layer "F.Fab") hide
        (effects (font (size 0.7 0.7) (thickness 0.15)) (justify left bottom))
    )
    (pad "1" smd circle (at 0 0) (size 0.75 0.75) (layers "F.Cu" "F.Mask")
      (net 133 "/Debug and JTAG/VCC_PD") (pinfunction "1") (pintype "passive"))
  )
	(footprint "kria-k26-devboard-footprints:TP_SMD_0.75mm" (layer "F.Cu")
    (at 151.5 113.45)
    (property "Author" "Antmicro")
    (property "License" "Apache-2.0")
    (property "MPN" "")
    (property "Manufacturer" "")
    (property "Sheetfile" "debug.kicad_sch")
    (property "Sheetname" "Debug and JTAG")
    (property "ki_description" "Test Point 0.75mm")
    (attr exclude_from_pos_files)
    (fp_text reference "TP28" (at 0.26 0.37) (layer "F.SilkS")
        (effects (font (size 0.7 0.7) (thickness 0.15)) (justify left bottom))
    )
    (fp_text value "TP_0.75mm_SMD" (at 0 1.2) (layer "F.Fab") hide
        (effects (font (size 0.7 0.7) (thickness 0.15)) (justify left bottom))
    )
    (fp_text user "Author: Antmicro" (at -0.4 3.901) (layer "F.Fab") hide
        (effects (font (size 0.7 0.7) (thickness 0.15)) (justify left bottom))
    )
    (fp_text user "${REFERENCE}" (at -0.4 2.7) (layer "F.Fab") hide
        (effects (font (size 0.7 0.7) (thickness 0.15)) (justify left bottom))
    )
    (fp_text user "License: Apache-2.0" (at -0.4 5.101) (layer "F.Fab") hide
        (effects (font (size 0.7 0.7) (thickness 0.15)) (justify left bottom))
    )
    (pad "1" smd circle (at 0 0) (size 0.75 0.75) (layers "F.Cu" "F.Mask")
      (net 135 "/Debug and JTAG/VCC_USB") (pinfunction "1") (pintype "passive"))
  )
	(footprint "kria-k26-devboard-footprints:Nexperia_SOD128" (layer "F.Cu")
    (at 185.865 124 -90)
    (property "Author" "Antmicro")
    (property "DNP" "DNP")
    (property "License" "Apache-2.0")
    (property "MPN" "PMEG3050EP,115")
    (property "Manufacturer" "Nexperia")
    (property "Sheetfile" "supply-oring.kicad_sch")
    (property "Sheetname" "Supply ORing")
    (property "dnp" "")
    (property "exclude_from_bom" "")
    (property "ki_description" "SCHOTTKY RECT 30V 5A, Vf=315 mV")
    (attr exclude_from_pos_files exclude_from_bom)
    (fp_text reference "D23" (at 2.65 -2.425 90) (layer "F.SilkS")
        (effects (font (size 0.7 0.7) (thickness 0.15)) (justify left bottom))
    )
    (fp_text value "PMEG3050EP,115" (at -4.37 2.5 -90) (layer "F.Fab") hide
        (effects (font (size 0.7 0.7) (thickness 0.15)) (justify left bottom))
    )
    (fp_text user "Author: Antmicro" (at -4.37 4.5 -90) (layer "F.Fab") hide
        (effects (font (size 0.7 0.7) (thickness 0.15)) (justify left bottom))
    )
    (fp_text user "License: Apache-2.0" (at -4.37 5.7 -90) (layer "F.Fab") hide
        (effects (font (size 0.7 0.7) (thickness 0.15)) (justify left bottom))
    )
    (fp_text user "${REFERENCE}" (at -4.37 6.9 -90) (layer "F.Fab") hide
        (effects (font (size 0.7 0.7) (thickness 0.15)) (justify left bottom))
    )
    (fp_line (start -2.121 -1.474) (end -2.121 -1.287)
      (stroke (width 0.15) (type solid)) (layer "F.SilkS"))
    (fp_line (start -2.121 1.284) (end -2.121 1.473)
      (stroke (width 0.15) (type solid)) (layer "F.SilkS"))
    (fp_line (start -2.121 1.473) (end 2.12 1.473)
      (stroke (width 0.15) (type solid)) (layer "F.SilkS"))
    (fp_line (start -1.6 -1.4) (end -1.6 1.4)
      (stroke (width 0.12) (type solid)) (layer "F.SilkS"))
    (fp_line (start 2.12 -1.474) (end -2.121 -1.474)
      (stroke (width 0.15) (type solid)) (layer "F.SilkS"))
    (fp_line (start 2.12 -1.287) (end 2.12 -1.474)
      (stroke (width 0.15) (type solid)) (layer "F.SilkS"))
    (fp_line (start 2.12 1.473) (end 2.12 1.284)
      (stroke (width 0.15) (type solid)) (layer "F.SilkS"))
    (fp_rect (start -2.8 -1.6) (end 2.8 1.6)
      (stroke (width 0.05) (type solid)) (fill none) (layer "F.CrtYd"))
    (fp_line (start -2.503 -0.954) (end -2.503 0.952)
      (stroke (width 0.15) (type solid)) (layer "F.Fab"))
    (fp_line (start -2.503 0.952) (end -1.994 0.952)
      (stroke (width 0.15) (type solid)) (layer "F.Fab"))
    (fp_line (start -1.994 -1.347) (end -1.994 1.346)
      (stroke (width 0.15) (type solid)) (layer "F.Fab"))
    (fp_line (start -1.994 -0.954) (end -2.503 -0.954)
      (stroke (width 0.15) (type solid)) (layer "F.Fab"))
    (fp_line (start -1.994 -0.675) (end -1.321 -1.347)
      (stroke (width 0.15) (type solid)) (layer "F.Fab"))
    (fp_line (start -1.994 0.673) (end -1.321 1.346)
      (stroke (width 0.15) (type solid)) (layer "F.Fab"))
    (fp_line (start -1.994 0.952) (end -1.994 -0.954)
      (stroke (width 0.15) (type solid)) (layer "F.Fab"))
    (fp_line (start -1.994 1.346) (end 1.993 1.346)
      (stroke (width 0.15) (type solid)) (layer "F.Fab"))
    (fp_line (start 1.993 -1.347) (end -1.994 -1.347)
      (stroke (width 0.15) (type solid)) (layer "F.Fab"))
    (fp_line (start 1.993 -0.954) (end 1.993 0.952)
      (stroke (width 0.15) (type solid)) (layer "F.Fab"))
    (fp_line (start 1.993 0.952) (end 2.5 0.952)
      (stroke (width 0.15) (type solid)) (layer "F.Fab"))
    (fp_line (start 1.993 1.346) (end 1.993 -1.347)
      (stroke (width 0.15) (type solid)) (layer "F.Fab"))
    (fp_line (start 2.5 -0.954) (end 1.993 -0.954)
      (stroke (width 0.15) (type solid)) (layer "F.Fab"))
    (fp_line (start 2.5 0.952) (end 2.5 -0.954)
      (stroke (width 0.15) (type solid)) (layer "F.Fab"))
    (pad "1" smd rect (at -2.298 0 270) (size 0.8096 1.905) (layers "F.Cu" "F.Paste" "F.Mask")
      (net 14 "/Power Supply/DC/DC conventers/DC_MAIN_BUS") (pinfunction "1") (pintype "passive"))
    (pad "2" smd rect (at 2.297 0 270) (size 0.8096 1.905) (layers "F.Cu" "F.Paste" "F.Mask")
      (net 13 "/Power Supply/PoE/POE_12V") (pinfunction "2") (pintype "passive"))
  )
	(footprint "kria-k26-devboard-footprints:C_0402_1005Metric" (layer "F.Cu")
    (at 186.9 114.77)
    (descr "Capacitor SMD 0402")
    (tags "capacitor SMD 0402")
    (property "Author" "Antmicro")
    (property "Dielectric" "X5R")
    (property "License" "Apache-2.0")
    (property "MPN" "GRM155R61H104KE14D")
    (property "Manufacturer" "Murata")
    (property "Sheetfile" "PoE.kicad_sch")
    (property "Sheetname" "PoE")
    (property "Val" "100n")
    (property "Voltage" "50V")
    (property "ki_description" "SMD Multilayer Ceramic Capacitor, 0.1 µF, 50 V, 0402 [1005 Metric], ± 10%, X5R, GRM Series")
    (property "ki_keywords" "0402, SMT, CAPACITOR, PASSIVE, CERAMIC, MLCC")
    (attr smd)
    (fp_text reference "C182" (at -1.48 -0.37) (layer "F.SilkS")
        (effects (font (size 0.7 0.7) (thickness 0.15)) (justify left bottom))
    )
    (fp_text value "C_100n_0402" (at 0 1.4) (layer "F.Fab") hide
        (effects (font (size 0.7 0.7) (thickness 0.15)) (justify left bottom))
    )
    (fp_text user "${REFERENCE}" (at -0.932 3.168) (layer "F.Fab") hide
        (effects (font (size 0.7 0.7) (thickness 0.15)) (justify left bottom))
    )
    (fp_text user "License: Apache-2.0" (at -0.932 5.17) (layer "F.Fab") hide
        (effects (font (size 0.7 0.7) (thickness 0.15)) (justify left bottom))
    )
    (fp_text user "Author: Antmicro" (at -0.932 4.17) (layer "F.Fab") hide
        (effects (font (size 0.7 0.7) (thickness 0.15)) (justify left bottom))
    )
    (fp_rect (start -0.94 -0.47) (end 0.94 0.47)
      (stroke (width 0.05) (type solid)) (fill none) (layer "F.CrtYd"))
    (fp_rect (start -0.499 -0.249) (end 0.499 0.249)
      (stroke (width 0.15) (type solid)) (fill none) (layer "F.Fab"))
    (pad "1" smd roundrect (at -0.484 0) (size 0.59 0.64) (layers "F.Cu" "F.Paste" "F.Mask") (roundrect_rratio 0.25)
      (net 13 "/Power Supply/PoE/POE_12V") (pintype "passive"))
    (pad "2" smd roundrect (at 0.484 0) (size 0.59 0.64) (layers "F.Cu" "F.Paste" "F.Mask") (roundrect_rratio 0.25)
      (net 1 "GND") (pintype "passive"))
  )
)
